(kicad_pcb
	(version 20221018)
	(generator pcbnew)
	(general
    (thickness 1.62)
  )
	(paper "A4")
	(title_block
    (title "ECP5 - Datacenter Secure Control Module (DC-SCM)")
    (date "2024-07-01")
    (rev "1.2.1")
		(comment 9 "footprints 42-45 of 506")
	)
	(layers
    (0 "F.Cu" signal)
    (1 "In1.Cu" power)
    (2 "In2.Cu" signal)
    (3 "In3.Cu" power)
    (4 "In4.Cu" power)
    (5 "In5.Cu" signal)
    (6 "In6.Cu" power)
    (31 "B.Cu" signal)
    (32 "B.Adhes" user "B.Adhesive")
    (33 "F.Adhes" user "F.Adhesive")
    (34 "B.Paste" user)
    (35 "F.Paste" user)
    (36 "B.SilkS" user "B.Silkscreen")
    (37 "F.SilkS" user "F.Silkscreen")
    (38 "B.Mask" user)
    (39 "F.Mask" user)
    (40 "Dwgs.User" user "User.Drawings")
    (41 "Cmts.User" user "User.Comments")
    (42 "Eco1.User" user "User.Eco1")
    (43 "Eco2.User" user "User.Eco2")
    (44 "Edge.Cuts" user)
    (45 "Margin" user)
    (46 "B.CrtYd" user "B.Courtyard")
    (47 "F.CrtYd" user "F.Courtyard")
    (48 "B.Fab" user)
    (49 "F.Fab" user)
  )
	(footprint "antmicro-footprints:LED_0603_1608Metric_G" (layer "F.Cu")
    (at 141.161 61.478 90)
    (descr "LED SMD 0603 Green")
    (tags "LED SMD 0603 Green")
    (property "Author" "Antmicro")
    (property "Color" "Green")
    (property "License" "Apache-2.0")
    (property "MPN" "LG L29K-G2J1-24-Z")
    (property "Manufacturer" "OSRAM")
    (property "Sheetfile" "interfaces.kicad_sch")
    (property "Sheetname" "Interfaces")
    (property "ki_description" "LED, Green, SMD, 0603, 20 mA, 1.7 V, 570 nm")
    (property "ki_keywords" "SMT, DIODE, SEMICONDUCTOR, LED")
    (attr smd)
    (fp_text reference "D4" (at 1.868 0.049) (layer "F.SilkS")
        (effects (font (size 0.7 0.7) (thickness 0.127)))
    )
    (fp_text value "LED_G_0603_LG_L29K-G2J1-24-Z" (at 0 1.77 90) (layer "F.Fab")
        (effects (font (size 1 1) (thickness 0.15)))
    )
    (fp_text user "License: Apache-2.0" (at -1.4224 3.599 90) (layer "F.Fab") hide
        (effects (font (size 0.7 0.7) (thickness 0.15)) (justify left bottom))
    )
    (fp_text user "Author: Antmicro" (at -1.4224 4.799 90) (layer "F.Fab") hide
        (effects (font (size 0.7 0.7) (thickness 0.15)) (justify left bottom))
    )
    (fp_text user "${REFERENCE}" (at -1.4224 5.999 90) (layer "F.Fab") hide
        (effects (font (size 0.7 0.7) (thickness 0.15)) (justify left bottom))
    )
    (fp_line (start -1.18 -0.319) (end -1.18 0.321)
      (stroke (width 0.15) (type solid)) (layer "F.SilkS"))
    (fp_line (start -0.094672 0.001008) (end -0.24 0.001008)
      (stroke (width 0.1) (type solid)) (layer "F.SilkS"))
    (fp_line (start -0.094672 0.001008) (end 0.105328 -0.198992)
      (stroke (width 0.1) (type solid)) (layer "F.SilkS"))
    (fp_line (start -0.094672 0.201008) (end -0.094672 -0.198992)
      (stroke (width 0.1) (type solid)) (layer "F.SilkS"))
    (fp_line (start 0.105328 0.001008) (end 0.24 0.001)
      (stroke (width 0.1) (type solid)) (layer "F.SilkS"))
    (fp_line (start 0.105328 0.201008) (end -0.094672 0.001008)
      (stroke (width 0.1) (type solid)) (layer "F.SilkS"))
    (fp_line (start 0.105328 0.201008) (end 0.105328 -0.198992)
      (stroke (width 0.1) (type solid)) (layer "F.SilkS"))
    (fp_line (start 0.22 -0.35) (end -0.22 -0.35)
      (stroke (width 0.15) (type solid)) (layer "F.SilkS"))
    (fp_line (start 0.22 0.35) (end -0.22 0.35)
      (stroke (width 0.15) (type solid)) (layer "F.SilkS"))
    (fp_rect (start 1.25 0.65) (end -1.25 -0.65)
      (stroke (width 0.05) (type solid)) (fill none) (layer "F.CrtYd"))
    (fp_line (start -0.199 -0.202) (end -0.199 0.1)
      (stroke (width 0.15) (type solid)) (layer "F.Fab"))
    (fp_line (start -0.199 0) (end -0.597 0)
      (stroke (width 0.15) (type solid)) (layer "F.Fab"))
    (fp_line (start -0.199 0.2) (end -0.199 0.1)
      (stroke (width 0.15) (type solid)) (layer "F.Fab"))
    (fp_line (start -0.101 0) (end 0.201 0.2)
      (stroke (width 0.15) (type solid)) (layer "F.Fab"))
    (fp_line (start 0.201 -0.202) (end -0.101 0)
      (stroke (width 0.15) (type solid)) (layer "F.Fab"))
    (fp_line (start 0.201 0) (end 0.201 -0.202)
      (stroke (width 0.15) (type solid)) (layer "F.Fab"))
    (fp_line (start 0.201 0.2) (end 0.201 0)
      (stroke (width 0.15) (type solid)) (layer "F.Fab"))
    (fp_line (start 0.599 0) (end 0.201 0)
      (stroke (width 0.15) (type solid)) (layer "F.Fab"))
    (fp_rect (start 0.848 0.4) (end -0.85 -0.402)
      (stroke (width 0.15) (type solid)) (fill none) (layer "F.Fab"))
    (pad "1" smd roundrect (at -0.7 0 270) (size 0.8 1) (layers "F.Cu" "F.Paste" "F.Mask") (roundrect_rratio 0.2)
      (net 311 "Net-(D4-C)") (pinfunction "C") (pintype "passive"))
    (pad "2" smd roundrect (at 0.7 0 270) (size 0.8 1) (layers "F.Cu" "F.Paste" "F.Mask") (roundrect_rratio 0.2)
      (net 312 "Net-(D4-A)") (pinfunction "A") (pintype "passive"))
  )
	(footprint "antmicro-footprints:LED_0603_1608Metric_G" (layer "F.Cu")
    (at 143.211 61.478 90)
    (descr "LED SMD 0603 Green")
    (tags "LED SMD 0603 Green")
    (property "Author" "Antmicro")
    (property "Color" "Green")
    (property "License" "Apache-2.0")
    (property "MPN" "LG L29K-G2J1-24-Z")
    (property "Manufacturer" "OSRAM")
    (property "Sheetfile" "interfaces.kicad_sch")
    (property "Sheetname" "Interfaces")
    (property "ki_description" "LED, Green, SMD, 0603, 20 mA, 1.7 V, 570 nm")
    (property "ki_keywords" "SMT, DIODE, SEMICONDUCTOR, LED")
    (attr smd)
    (fp_text reference "D5" (at 1.878 0.039) (layer "F.SilkS")
        (effects (font (size 0.7 0.7) (thickness 0.127)))
    )
    (fp_text value "LED_G_0603_LG_L29K-G2J1-24-Z" (at 0 1.77 90) (layer "F.Fab")
        (effects (font (size 1 1) (thickness 0.15)))
    )
    (fp_text user "Author: Antmicro" (at -1.4224 4.799 90) (layer "F.Fab") hide
        (effects (font (size 0.7 0.7) (thickness 0.15)) (justify left bottom))
    )
    (fp_text user "License: Apache-2.0" (at -1.4224 3.599 90) (layer "F.Fab") hide
        (effects (font (size 0.7 0.7) (thickness 0.15)) (justify left bottom))
    )
    (fp_text user "${REFERENCE}" (at -1.4224 5.999 90) (layer "F.Fab") hide
        (effects (font (size 0.7 0.7) (thickness 0.15)) (justify left bottom))
    )
    (fp_line (start -1.18 -0.319) (end -1.18 0.321)
      (stroke (width 0.15) (type solid)) (layer "F.SilkS"))
    (fp_line (start -0.094672 0.001008) (end -0.24 0.001008)
      (stroke (width 0.1) (type solid)) (layer "F.SilkS"))
    (fp_line (start -0.094672 0.001008) (end 0.105328 -0.198992)
      (stroke (width 0.1) (type solid)) (layer "F.SilkS"))
    (fp_line (start -0.094672 0.201008) (end -0.094672 -0.198992)
      (stroke (width 0.1) (type solid)) (layer "F.SilkS"))
    (fp_line (start 0.105328 0.001008) (end 0.24 0.001)
      (stroke (width 0.1) (type solid)) (layer "F.SilkS"))
    (fp_line (start 0.105328 0.201008) (end -0.094672 0.001008)
      (stroke (width 0.1) (type solid)) (layer "F.SilkS"))
    (fp_line (start 0.105328 0.201008) (end 0.105328 -0.198992)
      (stroke (width 0.1) (type solid)) (layer "F.SilkS"))
    (fp_line (start 0.22 -0.35) (end -0.22 -0.35)
      (stroke (width 0.15) (type solid)) (layer "F.SilkS"))
    (fp_line (start 0.22 0.35) (end -0.22 0.35)
      (stroke (width 0.15) (type solid)) (layer "F.SilkS"))
    (fp_rect (start 1.25 0.65) (end -1.25 -0.65)
      (stroke (width 0.05) (type solid)) (fill none) (layer "F.CrtYd"))
    (fp_line (start -0.199 -0.202) (end -0.199 0.1)
      (stroke (width 0.15) (type solid)) (layer "F.Fab"))
    (fp_line (start -0.199 0) (end -0.597 0)
      (stroke (width 0.15) (type solid)) (layer "F.Fab"))
    (fp_line (start -0.199 0.2) (end -0.199 0.1)
      (stroke (width 0.15) (type solid)) (layer "F.Fab"))
    (fp_line (start -0.101 0) (end 0.201 0.2)
      (stroke (width 0.15) (type solid)) (layer "F.Fab"))
    (fp_line (start 0.201 -0.202) (end -0.101 0)
      (stroke (width 0.15) (type solid)) (layer "F.Fab"))
    (fp_line (start 0.201 0) (end 0.201 -0.202)
      (stroke (width 0.15) (type solid)) (layer "F.Fab"))
    (fp_line (start 0.201 0.2) (end 0.201 0)
      (stroke (width 0.15) (type solid)) (layer "F.Fab"))
    (fp_line (start 0.599 0) (end 0.201 0)
      (stroke (width 0.15) (type solid)) (layer "F.Fab"))
    (fp_rect (start 0.848 0.4) (end -0.85 -0.402)
      (stroke (width 0.15) (type solid)) (fill none) (layer "F.Fab"))
    (pad "1" smd roundrect (at -0.7 0 270) (size 0.8 1) (layers "F.Cu" "F.Paste" "F.Mask") (roundrect_rratio 0.2)
      (net 313 "Net-(D5-C)") (pinfunction "C") (pintype "passive"))
    (pad "2" smd roundrect (at 0.7 0 270) (size 0.8 1) (layers "F.Cu" "F.Paste" "F.Mask") (roundrect_rratio 0.2)
      (net 314 "Net-(D5-A)") (pinfunction "A") (pintype "passive"))
  )
	(footprint "antmicro-footprints:SOT-23-3" (layer "F.Cu")
    (at 120.275 68.45)
    (property "Author" "Antmicro")
    (property "License" "Apache-2.0")
    (property "MPN" "2N7002")
    (property "Manufacturer" "ON Semiconductor")
    (property "Sheetfile" "interfaces.kicad_sch")
    (property "Sheetname" "Interfaces")
    (property "ki_description" "Power MOSFET, N Channel, 60 V, 115 mA, 1.2 ohm, SOT-23, Surface Mount")
    (property "ki_keywords" "SMT, TRANSISTOR, SEMICONDUCTOR, NMOS")
    (attr smd)
    (fp_text reference "Q1" (at -2.35 1.225 90) (layer "F.SilkS")
        (effects (font (size 0.7 0.7) (thickness 0.127)))
    )
    (fp_text value "2N7002_SOT-23-3" (at 0.025 3.25) (layer "F.Fab")
        (effects (font (size 1 1) (thickness 0.15)))
    )
    (fp_text user "License: Apache-2.0" (at -1.8 6.8) (layer "F.Fab") hide
        (effects (font (size 0.7 0.7) (thickness 0.15)) (justify left bottom))
    )
    (fp_text user "Author: Antmicro" (at -1.837 5.3) (layer "F.Fab") hide
        (effects (font (size 0.7 0.7) (thickness 0.15)) (justify left bottom))
    )
    (fp_text user "${REFERENCE}" (at -0.125 0.15) (layer "F.Fab")
        (effects (font (size 0.25 0.25) (thickness 0.05)))
    )
    (fp_line (start -1.45 -1.35) (end -0.85 -1.35)
      (stroke (width 0.15) (type solid)) (layer "F.SilkS"))
    (fp_line (start -0.85 -1.35) (end -0.7 -1.5)
      (stroke (width 0.15) (type solid)) (layer "F.SilkS"))
    (fp_line (start -0.7 1.5) (end -0.7 1.35)
      (stroke (width 0.15) (type solid)) (layer "F.SilkS"))
    (fp_line (start 0.7 -1.5) (end -0.7 -1.5)
      (stroke (width 0.15) (type solid)) (layer "F.SilkS"))
    (fp_line (start 0.7 -0.4) (end 0.7 -1.5)
      (stroke (width 0.15) (type solid)) (layer "F.SilkS"))
    (fp_line (start 0.7 0.4) (end 0.7 1.5)
      (stroke (width 0.15) (type solid)) (layer "F.SilkS"))
    (fp_line (start 0.7 1.5) (end -0.7 1.5)
      (stroke (width 0.15) (type solid)) (layer "F.SilkS"))
    (fp_line (start -1.75 -0.5) (end -1.75 -1.4)
      (stroke (width 0.05) (type solid)) (layer "F.CrtYd"))
    (fp_line (start -1.75 0.5) (end -0.85 0.5)
      (stroke (width 0.05) (type solid)) (layer "F.CrtYd"))
    (fp_line (start -1.75 1.4) (end -1.75 0.5)
      (stroke (width 0.05) (type solid)) (layer "F.CrtYd"))
    (fp_line (start -0.9 -1.6) (end -0.9 -1.4)
      (stroke (width 0.05) (type solid)) (layer "F.CrtYd"))
    (fp_line (start -0.9 -1.6) (end 0.825 -1.6)
      (stroke (width 0.05) (type solid)) (layer "F.CrtYd"))
    (fp_line (start -0.9 -1.4) (end -1.75 -1.4)
      (stroke (width 0.05) (type solid)) (layer "F.CrtYd"))
    (fp_line (start -0.85 -0.5) (end -1.75 -0.5)
      (stroke (width 0.05) (type solid)) (layer "F.CrtYd"))
    (fp_line (start -0.85 0.5) (end -0.85 -0.5)
      (stroke (width 0.05) (type solid)) (layer "F.CrtYd"))
    (fp_line (start -0.85 1.4) (end -1.75 1.4)
      (stroke (width 0.05) (type solid)) (layer "F.CrtYd"))
    (fp_line (start -0.85 1.65) (end -0.85 1.4)
      (stroke (width 0.05) (type solid)) (layer "F.CrtYd"))
    (fp_line (start 0.825 -1.6) (end 0.825 -0.45)
      (stroke (width 0.05) (type solid)) (layer "F.CrtYd"))
    (fp_line (start 0.825 -0.45) (end 1.75 -0.45)
      (stroke (width 0.05) (type solid)) (layer "F.CrtYd"))
    (fp_line (start 0.85 0.45) (end 0.85 1.65)
      (stroke (width 0.05) (type solid)) (layer "F.CrtYd"))
    (fp_line (start 0.85 1.65) (end -0.85 1.65)
      (stroke (width 0.05) (type solid)) (layer "F.CrtYd"))
    (fp_line (start 1.75 -0.45) (end 1.75 0.45)
      (stroke (width 0.05) (type solid)) (layer "F.CrtYd"))
    (fp_line (start 1.75 0.45) (end 0.85 0.45)
      (stroke (width 0.05) (type solid)) (layer "F.CrtYd"))
    (fp_line (start -0.712 -1.325) (end -0.712 1.523)
      (stroke (width 0.15) (type solid)) (layer "F.Fab"))
    (fp_line (start -0.712 1.519) (end 0.688 1.519)
      (stroke (width 0.15) (type solid)) (layer "F.Fab"))
    (fp_line (start -0.437 -1.526) (end -0.712 -1.325)
      (stroke (width 0.15) (type solid)) (layer "F.Fab"))
    (fp_line (start -0.437 -1.526) (end 0.688 -1.526)
      (stroke (width 0.15) (type solid)) (layer "F.Fab"))
    (fp_line (start 0.688 1.519) (end 0.688 -1.52)
      (stroke (width 0.15) (type solid)) (layer "F.Fab"))
    (pad "1" smd roundrect (at -1.1 -0.951) (size 1 0.6) (layers "F.Cu" "F.Paste" "F.Mask") (roundrect_rratio 0.15)
      (net 293 "USR_LED0") (pinfunction "G") (pintype "passive"))
    (pad "2" smd roundrect (at -1.1 0.949) (size 1 0.6) (layers "F.Cu" "F.Paste" "F.Mask") (roundrect_rratio 0.15)
      (net 1 "GND") (pinfunction "S") (pintype "passive"))
    (pad "3" smd roundrect (at 1.1 -0.0005) (size 1 0.6) (layers "F.Cu" "F.Paste" "F.Mask") (roundrect_rratio 0.15)
      (net 309 "Net-(D3-C)") (pinfunction "D") (pintype "passive"))
  )
	(footprint "antmicro-footprints:SOT-23-3" (layer "F.Cu")
    (at 120.275 72.475)
    (property "Author" "Antmicro")
    (property "License" "Apache-2.0")
    (property "MPN" "2N7002")
    (property "Manufacturer" "ON Semiconductor")
    (property "Sheetfile" "interfaces.kicad_sch")
    (property "Sheetname" "Interfaces")
    (property "ki_description" "Power MOSFET, N Channel, 60 V, 115 mA, 1.2 ohm, SOT-23, Surface Mount")
    (property "ki_keywords" "SMT, TRANSISTOR, SEMICONDUCTOR, NMOS")
    (attr smd)
    (fp_text reference "Q2" (at -2.35 1.075 90) (layer "F.SilkS")
        (effects (font (size 0.7 0.7) (thickness 0.127)))
    )
    (fp_text value "2N7002_SOT-23-3" (at 0.025 3.25) (layer "F.Fab")
        (effects (font (size 1 1) (thickness 0.15)))
    )
    (fp_text user "License: Apache-2.0" (at -1.8 6.8) (layer "F.Fab") hide
        (effects (font (size 0.7 0.7) (thickness 0.15)) (justify left bottom))
    )
    (fp_text user "Author: Antmicro" (at -1.837 5.3) (layer "F.Fab") hide
        (effects (font (size 0.7 0.7) (thickness 0.15)) (justify left bottom))
    )
    (fp_text user "${REFERENCE}" (at -0.125 0.15) (layer "F.Fab")
        (effects (font (size 0.25 0.25) (thickness 0.05)))
    )
    (fp_line (start -1.45 -1.35) (end -0.85 -1.35)
      (stroke (width 0.15) (type solid)) (layer "F.SilkS"))
    (fp_line (start -0.85 -1.35) (end -0.7 -1.5)
      (stroke (width 0.15) (type solid)) (layer "F.SilkS"))
    (fp_line (start -0.7 1.5) (end -0.7 1.35)
      (stroke (width 0.15) (type solid)) (layer "F.SilkS"))
    (fp_line (start 0.7 -1.5) (end -0.7 -1.5)
      (stroke (width 0.15) (type solid)) (layer "F.SilkS"))
    (fp_line (start 0.7 -0.4) (end 0.7 -1.5)
      (stroke (width 0.15) (type solid)) (layer "F.SilkS"))
    (fp_line (start 0.7 0.4) (end 0.7 1.5)
      (stroke (width 0.15) (type solid)) (layer "F.SilkS"))
    (fp_line (start 0.7 1.5) (end -0.7 1.5)
      (stroke (width 0.15) (type solid)) (layer "F.SilkS"))
    (fp_line (start -1.75 -0.5) (end -1.75 -1.4)
      (stroke (width 0.05) (type solid)) (layer "F.CrtYd"))
    (fp_line (start -1.75 0.5) (end -0.85 0.5)
      (stroke (width 0.05) (type solid)) (layer "F.CrtYd"))
    (fp_line (start -1.75 1.4) (end -1.75 0.5)
      (stroke (width 0.05) (type solid)) (layer "F.CrtYd"))
    (fp_line (start -0.9 -1.6) (end -0.9 -1.4)
      (stroke (width 0.05) (type solid)) (layer "F.CrtYd"))
    (fp_line (start -0.9 -1.6) (end 0.825 -1.6)
      (stroke (width 0.05) (type solid)) (layer "F.CrtYd"))
    (fp_line (start -0.9 -1.4) (end -1.75 -1.4)
      (stroke (width 0.05) (type solid)) (layer "F.CrtYd"))
    (fp_line (start -0.85 -0.5) (end -1.75 -0.5)
      (stroke (width 0.05) (type solid)) (layer "F.CrtYd"))
    (fp_line (start -0.85 0.5) (end -0.85 -0.5)
      (stroke (width 0.05) (type solid)) (layer "F.CrtYd"))
    (fp_line (start -0.85 1.4) (end -1.75 1.4)
      (stroke (width 0.05) (type solid)) (layer "F.CrtYd"))
    (fp_line (start -0.85 1.65) (end -0.85 1.4)
      (stroke (width 0.05) (type solid)) (layer "F.CrtYd"))
    (fp_line (start 0.825 -1.6) (end 0.825 -0.45)
      (stroke (width 0.05) (type solid)) (layer "F.CrtYd"))
    (fp_line (start 0.825 -0.45) (end 1.75 -0.45)
      (stroke (width 0.05) (type solid)) (layer "F.CrtYd"))
    (fp_line (start 0.85 0.45) (end 0.85 1.65)
      (stroke (width 0.05) (type solid)) (layer "F.CrtYd"))
    (fp_line (start 0.85 1.65) (end -0.85 1.65)
      (stroke (width 0.05) (type solid)) (layer "F.CrtYd"))
    (fp_line (start 1.75 -0.45) (end 1.75 0.45)
      (stroke (width 0.05) (type solid)) (layer "F.CrtYd"))
    (fp_line (start 1.75 0.45) (end 0.85 0.45)
      (stroke (width 0.05) (type solid)) (layer "F.CrtYd"))
    (fp_line (start -0.712 -1.325) (end -0.712 1.523)
      (stroke (width 0.15) (type solid)) (layer "F.Fab"))
    (fp_line (start -0.712 1.519) (end 0.688 1.519)
      (stroke (width 0.15) (type solid)) (layer "F.Fab"))
    (fp_line (start -0.437 -1.526) (end -0.712 -1.325)
      (stroke (width 0.15) (type solid)) (layer "F.Fab"))
    (fp_line (start -0.437 -1.526) (end 0.688 -1.526)
      (stroke (width 0.15) (type solid)) (layer "F.Fab"))
    (fp_line (start 0.688 1.519) (end 0.688 -1.52)
      (stroke (width 0.15) (type solid)) (layer "F.Fab"))
    (pad "1" smd roundrect (at -1.1 -0.951) (size 1 0.6) (layers "F.Cu" "F.Paste" "F.Mask") (roundrect_rratio 0.15)
      (net 294 "USR_LED1") (pinfunction "G") (pintype "passive"))
    (pad "2" smd roundrect (at -1.1 0.949) (size 1 0.6) (layers "F.Cu" "F.Paste" "F.Mask") (roundrect_rratio 0.15)
      (net 1 "GND") (pinfunction "S") (pintype "passive"))
    (pad "3" smd roundrect (at 1.1 -0.0005) (size 1 0.6) (layers "F.Cu" "F.Paste" "F.Mask") (roundrect_rratio 0.15)
      (net 311 "Net-(D4-C)") (pinfunction "D") (pintype "passive"))
  )
)
